# S9S_MB_2U (Grand Teton) — schematic netlist excerpt (pin names and nets, part order shuffled) for the footprints in the layout excerpt that follows; sources: Cadence DE-HDL packaged netlist, KiCad conversion of 03242023_DA0F0TMBIJ0_F0T_Motherboard_J_brd_V01_OCP.brd

R4491  Q_RES  10K 1% CHIP  pkg 0402LF  page 211 : A = P3V3 ; B = CLK_9ZXL045_HIBW
C701  Q_CAP_DIFFBUS  DIFF BUS_0.22UF 6.3V 20% X6S  pkg C0201  page 177 : \1\ = P5E_CPU1_PE4_TX_C_DP<4> ; \2\ = P5E_CPU1_PE4_TX_DP<4>
PR1329  Q_RES  5.1 5% CHIP  pkg 0402LF  page 263 : A = PVCC1_AUX ; B = P1V8_PCH_AUX_VCC

(kicad_pcb
	(version 20260206)
	(generator "pcbnew")
	(generator_version "10.0")
	(general
		(thickness 1.6)
		(legacy_teardrops no)
	)
	(paper "A4")
	(title_block
		(title "03242023_DA0F0TMBIJ0_F0T_Motherboard_J_brd_V01_OCP.brd")
		(comment 1 "Grand Teton / footprints 2010-2012 of 6105")
	)
	(layers
		(0 "F.Cu" signal "TOP")
		(4 "In1.Cu" signal "GND")
		(6 "In2.Cu" signal "IN1")
		(8 "In3.Cu" signal "GND1")
		(10 "In4.Cu" signal "IN2")
		(12 "In5.Cu" signal "GND2")
		(14 "In6.Cu" signal "IN3")
		(16 "In7.Cu" signal "GND3")
		(18 "In8.Cu" signal "VCC")
		(20 "In9.Cu" signal "VCC1")
		(22 "In10.Cu" signal "GND4")
		(24 "In11.Cu" signal "IN4")
		(26 "In12.Cu" signal "GND5")
		(28 "In13.Cu" signal "IN5")
		(30 "In14.Cu" signal "GND6")
		(32 "In15.Cu" signal "IN6")
		(34 "In16.Cu" signal "GND7")
		(2 "B.Cu" signal "BOTTOM")
		(9 "F.Adhes" user "F.Adhesive")
		(11 "B.Adhes" user "B.Adhesive")
		(13 "F.Paste" user "Package Geometry/Pastemask Top")
		(15 "B.Paste" user "Package Geometry/Pastemask Bottom")
		(5 "F.SilkS" user "Ref Des/Silkscreen Top")
		(7 "B.SilkS" user "Ref Des/Silkscreen Bottom")
		(1 "F.Mask" user "Board Geometry/Soldermask Top")
		(3 "B.Mask" user "Board Geometry/Soldermask Bottom")
		(17 "Dwgs.User" user "User.Drawings")
		(19 "Cmts.User" user "User.Comments")
		(21 "Eco1.User" user "User.Eco1")
		(23 "Eco2.User" user "User.Eco2")
		(25 "Edge.Cuts" user "Board Geometry/Outline")
		(27 "Margin" user)
		(31 "F.CrtYd" user "Package Geometry/Place Bound Top")
		(29 "B.CrtYd" user "Package Geometry/Place Bound Bottom")
		(35 "F.Fab" user "Ref Des/Assembly Top")
		(33 "B.Fab" user "Ref Des/Assembly Bottom")
	)
	(footprint ""
		(layer "F.Cu")
		(at 382.086612 -72.75957 90)
		(property "Reference" "PR1329"
			(at 0 0 90)
			(layer "F.SilkS")
			(hide yes)
			(effects
				(font
					(size 1.27 1.27)
				)
			)
		)
		(property "Value" ""
			(at 0 0 90)
			(layer "F.Fab")
			(effects
				(font
					(size 1.27 1.27)
				)
			)
		)
		(duplicate_pad_numbers_are_jumpers no)
		(fp_line
			(start 0.7874 -0.4064)
			(end 0.7874 0.4064)
			(stroke
				(width 0.1524)
				(type default)
			)
			(layer "F.SilkS")
		)
		(fp_line
			(start -0.7874 -0.4064)
			(end 0.7874 -0.4064)
			(stroke
				(width 0.1524)
				(type default)
			)
			(layer "F.SilkS")
		)
		(fp_line
			(start 0.7874 0.4064)
			(end -0.7874 0.4064)
			(stroke
				(width 0.1524)
				(type default)
			)
			(layer "F.SilkS")
		)
		(fp_line
			(start -0.7874 0.4064)
			(end -0.7874 -0.4064)
			(stroke
				(width 0.1524)
				(type default)
			)
			(layer "F.SilkS")
		)
		(fp_line
			(start -0.12065 -0.305054)
			(end -0.12065 -0.2794)
			(stroke
				(width 0.1)
				(type default)
			)
			(layer "F.Fab")
		)
		(fp_line
			(start -0.67945 -0.305054)
			(end -0.12065 -0.305054)
			(stroke
				(width 0.1)
				(type default)
			)
			(layer "F.Fab")
		)
		(fp_line
			(start 0.67945 -0.3048)
			(end 0.67945 0.3048)
			(stroke
				(width 0.1)
				(type default)
			)
			(layer "F.Fab")
		)
		(fp_line
			(start 0.12065 -0.3048)
			(end 0.67945 -0.3048)
			(stroke
				(width 0.1)
				(type default)
			)
			(layer "F.Fab")
		)
		(fp_line
			(start 0.12065 -0.2794)
			(end 0.12065 -0.3048)
			(stroke
				(width 0.1)
				(type default)
			)
			(layer "F.Fab")
		)
		(fp_line
			(start -0.12065 -0.2794)
			(end 0.12065 -0.2794)
			(stroke
				(width 0.1)
				(type default)
			)
			(layer "F.Fab")
		)
		(fp_line
			(start 0.120396 0.2794)
			(end -0.12065 0.2794)
			(stroke
				(width 0.1)
				(type default)
			)
			(layer "F.Fab")
		)
		(fp_line
			(start -0.12065 0.2794)
			(end -0.12065 0.3048)
			(stroke
				(width 0.1)
				(type default)
			)
			(layer "F.Fab")
		)
		(fp_line
			(start 0.67945 0.3048)
			(end 0.120396 0.3048)
			(stroke
				(width 0.1)
				(type default)
			)
			(layer "F.Fab")
		)
		(fp_line
			(start 0.120396 0.3048)
			(end 0.120396 0.2794)
			(stroke
				(width 0.1)
				(type default)
			)
			(layer "F.Fab")
		)
		(fp_line
			(start -0.12065 0.3048)
			(end -0.67945 0.3048)
			(stroke
				(width 0.1)
				(type default)
			)
			(layer "F.Fab")
		)
		(fp_line
			(start -0.67945 0.3048)
			(end -0.67945 -0.305054)
			(stroke
				(width 0.1)
				(type default)
			)
			(layer "F.Fab")
		)
		(pad "1" smd circle
			(at -0.40005 0 90)
			(size 0 0)
			(layers "F.Cu" "F.Mask" "F.Paste")
			(net "PVCC1_AUX")
		)
		(pad "2" smd circle
			(at 0.40005 0 90)
			(size 0 0)
			(layers "F.Cu" "F.Mask" "F.Paste")
			(net "P1V8_PCH_AUX_VCC")
		)
	)
	(footprint ""
		(layer "F.Cu")
		(at 62.467998 -408.517344 -90)
		(property "Reference" "C701"
			(at 0 0 270)
			(layer "F.SilkS")
			(hide yes)
			(effects
				(font
					(size 1.27 1.27)
				)
			)
		)
		(property "Value" ""
			(at 0 0 270)
			(layer "F.Fab")
			(effects
				(font
					(size 1.27 1.27)
				)
			)
		)
		(duplicate_pad_numbers_are_jumpers no)
		(fp_line
			(start -0.299974 0.150114)
			(end -0.299974 -0.150114)
			(stroke
				(width 0.1)
				(type default)
			)
			(layer "F.Fab")
		)
		(fp_line
			(start 0.299974 0.150114)
			(end -0.299974 0.150114)
			(stroke
				(width 0.1)
				(type default)
			)
			(layer "F.Fab")
		)
		(fp_line
			(start -0.299974 -0.150114)
			(end 0.299974 -0.150114)
			(stroke
				(width 0.1)
				(type default)
			)
			(layer "F.Fab")
		)
		(fp_line
			(start 0.299974 -0.150114)
			(end 0.299974 0.150114)
			(stroke
				(width 0.1)
				(type default)
			)
			(layer "F.Fab")
		)
		(pad "1" smd rect
			(at -0.2667 0 270)
			(size 0.3048 0.381)
			(layers "F.Cu" "F.Mask" "F.Paste")
			(net "P5E_CPU1_PE4_TX_C_DP<4>")
		)
		(pad "2" smd rect
			(at 0.2667 0 270)
			(size 0.3048 0.381)
			(layers "F.Cu" "F.Mask" "F.Paste")
			(net "P5E_CPU1_PE4_TX_DP<4>")
		)
	)
	(footprint ""
		(layer "F.Cu")
		(at 118.83898 -412.17469 180)
		(property "Reference" "R4491"
			(at 0 0 180)
			(layer "F.SilkS")
			(hide yes)
			(effects
				(font
					(size 1.27 1.27)
				)
			)
		)
		(property "Value" ""
			(at 0 0 180)
			(layer "F.Fab")
			(effects
				(font
					(size 1.27 1.27)
				)
			)
		)
		(duplicate_pad_numbers_are_jumpers no)
		(fp_line
			(start 0.7874 0.4064)
			(end -0.7874 0.4064)
			(stroke
				(width 0.1524)
				(type default)
			)
			(layer "F.SilkS")
		)
		(fp_line
			(start 0.7874 -0.4064)
			(end 0.7874 0.4064)
			(stroke
				(width 0.1524)
				(type default)
			)
			(layer "F.SilkS")
		)
		(fp_line
			(start -0.7874 0.4064)
			(end -0.7874 -0.4064)
			(stroke
				(width 0.1524)
				(type default)
			)
			(layer "F.SilkS")
		)
		(fp_line
			(start -0.7874 -0.4064)
			(end 0.7874 -0.4064)
			(stroke
				(width 0.1524)
				(type default)
			)
			(layer "F.SilkS")
		)
		(fp_line
			(start 0.67945 0.3048)
			(end 0.120396 0.3048)
			(stroke
				(width 0.1)
				(type default)
			)
			(layer "F.Fab")
		)
		(fp_line
			(start 0.67945 -0.3048)
			(end 0.67945 0.3048)
			(stroke
				(width 0.1)
				(type default)
			)
			(layer "F.Fab")
		)
		(fp_line
			(start 0.12065 -0.2794)
			(end 0.12065 -0.3048)
			(stroke
				(width 0.1)
				(type default)
			)
			(layer "F.Fab")
		)
		(fp_line
			(start 0.12065 -0.3048)
			(end 0.67945 -0.3048)
			(stroke
				(width 0.1)
				(type default)
			)
			(layer "F.Fab")
		)
		(fp_line
			(start 0.120396 0.3048)
			(end 0.120396 0.2794)
			(stroke
				(width 0.1)
				(type default)
			)
			(layer "F.Fab")
		)
		(fp_line
			(start 0.120396 0.2794)
			(end -0.12065 0.2794)
			(stroke
				(width 0.1)
				(type default)
			)
			(layer "F.Fab")
		)
		(fp_line
			(start -0.12065 0.3048)
			(end -0.67945 0.3048)
			(stroke
				(width 0.1)
				(type default)
			)
			(layer "F.Fab")
		)
		(fp_line
			(start -0.12065 0.2794)
			(end -0.12065 0.3048)
			(stroke
				(width 0.1)
				(type default)
			)
			(layer "F.Fab")
		)
		(fp_line
			(start -0.12065 -0.2794)
			(end 0.12065 -0.2794)
			(stroke
				(width 0.1)
				(type default)
			)
			(layer "F.Fab")
		)
		(fp_line
			(start -0.12065 -0.305054)
			(end -0.12065 -0.2794)
			(stroke
				(width 0.1)
				(type default)
			)
			(layer "F.Fab")
		)
		(fp_line
			(start -0.67945 0.3048)
			(end -0.67945 -0.305054)
			(stroke
				(width 0.1)
				(type default)
			)
			(layer "F.Fab")
		)
		(fp_line
			(start -0.67945 -0.305054)
			(end -0.12065 -0.305054)
			(stroke
				(width 0.1)
				(type default)
			)
			(layer "F.Fab")
		)
		(pad "1" smd circle
			(at -0.40005 0 180)
			(size 0 0)
			(layers "F.Cu" "F.Mask" "F.Paste")
			(net "P3V3")
		)
		(pad "2" smd circle
			(at 0.40005 0 180)
			(size 0 0)
			(layers "F.Cu" "F.Mask" "F.Paste")
			(net "CLK_9ZXL045_HIBW")
		)
	)
)
